(kicad_pcb
	(version 20241229)
	(generator "pcbnew")
	(generator_version "9.0")
	(general
		(thickness 1.599998)
		(legacy_teardrops no)
	)
	(paper "A4")
	(title_block
		(date "2023-02-12")
		(rev "1.1.5")
		(comment 9 "footprints 76-80 of 473")
	)
	(layers
		(0 "F.Cu" signal)
		(4 "In1.Cu" power "In1.GND")
		(6 "In2.Cu" signal)
		(8 "In3.Cu" power "In3.GND")
		(10 "In4.Cu" power "In4.VCC")
		(12 "In5.Cu" signal)
		(14 "In6.Cu" power "In6.VCC")
		(2 "B.Cu" signal)
		(9 "F.Adhes" user "F.Adhesive")
		(11 "B.Adhes" user "B.Adhesive")
		(13 "F.Paste" user)
		(15 "B.Paste" user)
		(5 "F.SilkS" user "F.Silkscreen")
		(7 "B.SilkS" user "B.Silkscreen")
		(1 "F.Mask" user)
		(3 "B.Mask" user)
		(17 "Dwgs.User" user "User.Drawings")
		(19 "Cmts.User" user "User.Comments")
		(21 "Eco1.User" user "User.Eco1")
		(23 "Eco2.User" user "User.Eco2")
		(25 "Edge.Cuts" user)
		(27 "Margin" user)
		(31 "F.CrtYd" user "F.Courtyard")
		(29 "B.CrtYd" user "B.Courtyard")
		(35 "F.Fab" user)
		(33 "B.Fab" user)
	)
	(footprint "antmicro-footprints:VSSOP-8_3x3mm_P0.65mm"
		(layer "F.Cu")
		(at 138.125 95.499)
		(property "Reference" "U7"
			(at 0 -2 0)
			(layer "F.SilkS")
			(effects
				(font
					(size 0.7 0.7)
					(thickness 0.15)
				)
				(justify left bottom)
			)
		)
		(property "Value" "LM3881MME_NOPB"
			(at 0 2.9 0)
			(layer "F.Fab")
			(effects
				(font
					(size 0.7 0.7)
					(thickness 0.15)
				)
				(justify left bottom)
			)
		)
		(property "Description" "Power Sequencer, 3-Monitors, 2.7V-5.5Vin,VSSOP-8"
			(at 0 0 0)
			(layer "F.Fab")
			(hide yes)
			(effects
				(font
					(size 1.27 1.27)
					(thickness 0.15)
				)
			)
		)
		(property "Author" "Antmicro"
			(at 0 0 0)
			(layer "F.Fab")
			(hide yes)
			(effects
				(font
					(size 1 1)
					(thickness 0.15)
				)
			)
		)
		(property "License" "Apache-2.0"
			(at 0 0 0)
			(layer "F.Fab")
			(hide yes)
			(effects
				(font
					(size 1 1)
					(thickness 0.15)
				)
			)
		)
		(property "MPN" "LM3881MME/NOPB"
			(at 0 0 0)
			(layer "F.Fab")
			(hide yes)
			(effects
				(font
					(size 1 1)
					(thickness 0.15)
				)
			)
		)
		(property "Manufacturer" "Texas Instruments"
			(at 0 0 0)
			(layer "F.Fab")
			(hide yes)
			(effects
				(font
					(size 1 1)
					(thickness 0.15)
				)
			)
		)
		(sheetname "Supply")
		(sheetfile "supply.kicad_sch")
		(attr smd)
		(fp_line
			(start -1.6 -1.625)
			(end 1.554 -1.625)
			(stroke
				(width 0.12)
				(type solid)
			)
			(layer "F.SilkS")
		)
		(fp_line
			(start -1.496 1.625)
			(end 1.554 1.625)
			(stroke
				(width 0.12)
				(type solid)
			)
			(layer "F.SilkS")
		)
		(fp_circle
			(center -2.1 -1.438)
			(end -2.05 -1.438)
			(stroke
				(width 0.12)
				(type solid)
			)
			(fill yes)
			(layer "F.SilkS")
		)
		(fp_rect
			(start -3 -1.838)
			(end 3 1.862)
			(stroke
				(width 0.05)
				(type solid)
			)
			(fill no)
			(layer "F.CrtYd")
		)
		(fp_line
			(start -1.497 -1.502)
			(end 1.504 -1.502)
			(stroke
				(width 0.15)
				(type solid)
			)
			(layer "F.Fab")
		)
		(fp_line
			(start -1.497 1.5)
			(end -1.497 -1.502)
			(stroke
				(width 0.15)
				(type solid)
			)
			(layer "F.Fab")
		)
		(fp_line
			(start 1.504 -1.502)
			(end 1.504 1.5)
			(stroke
				(width 0.15)
				(type solid)
			)
			(layer "F.Fab")
		)
		(fp_line
			(start 1.504 1.5)
			(end -1.497 1.5)
			(stroke
				(width 0.15)
				(type solid)
			)
			(layer "F.Fab")
		)
		(pad "1" smd rect
			(at -2.096 -0.975)
			(size 1.556504 0.457986)
			(layers "F.Cu" "F.Mask" "F.Paste")
			(net 463 "VCC5V0_INT")
			(pinfunction "VCC")
			(pintype "power_in")
		)
		(pad "2" smd roundrect
			(at -2.096 -0.326)
			(size 1.556504 0.457986)
			(layers "F.Cu" "F.Mask" "F.Paste")
			(roundrect_rratio 0.5)
			(net 466 "SYS_ON")
			(pinfunction "EN")
			(pintype "passive")
		)
		(pad "3" smd roundrect
			(at -2.096 0.325)
			(size 1.556504 0.457986)
			(layers "F.Cu" "F.Mask" "F.Paste")
			(roundrect_rratio 0.5)
			(net 5 "GND")
			(pinfunction "GND")
			(pintype "power_in")
		)
		(pad "4" smd roundrect
			(at -2.096 0.974)
			(size 1.556504 0.457986)
			(layers "F.Cu" "F.Mask" "F.Paste")
			(roundrect_rratio 0.5)
			(net 262 "Net-(U7-INV)")
			(pinfunction "INV")
			(pintype "input")
		)
		(pad "5" smd roundrect
			(at 2.105 0.974)
			(size 1.556504 0.457986)
			(layers "F.Cu" "F.Mask" "F.Paste")
			(roundrect_rratio 0.5)
			(net 58 "Net-(U7-TADJ)")
			(pinfunction "TADJ")
			(pintype "passive")
		)
		(pad "6" smd roundrect
			(at 2.105 0.325)
			(size 1.556504 0.457986)
			(layers "F.Cu" "F.Mask" "F.Paste")
			(roundrect_rratio 0.5)
			(net 470 "/Supply/VCC_IO_EN")
			(pinfunction "FLAG3")
			(pintype "open_collector")
		)
		(pad "7" smd roundrect
			(at 2.105 -0.326)
			(size 1.556504 0.457986)
			(layers "F.Cu" "F.Mask" "F.Paste")
			(roundrect_rratio 0.5)
			(net 469 "/Supply/VCC_AUX_EN")
			(pinfunction "FLAG2")
			(pintype "open_collector")
		)
		(pad "8" smd roundrect
			(at 2.105 -0.975)
			(size 1.556504 0.457986)
			(layers "F.Cu" "F.Mask" "F.Paste")
			(roundrect_rratio 0.5)
			(net 468 "/Supply/VCC_INT_EN")
			(pinfunction "FLAG1")
			(pintype "open_collector")
		)
	)
	(footprint "antmicro-footprints:C_0603_1608Metric"
		(layer "F.Cu")
		(at 175.026 132.368 -90)
		(descr "Capacitor SMD 0603")
		(tags "capacitor 0603")
		(property "Reference" "C21"
			(at -0.968 -0.374 270)
			(layer "F.SilkS")
			(effects
				(font
					(size 0.7 0.7)
					(thickness 0.15)
				)
				(justify left bottom)
			)
		)
		(property "Value" "C_1u_0603"
			(at 0 1.6 270)
			(layer "F.Fab")
			(effects
				(font
					(size 0.7 0.7)
					(thickness 0.15)
				)
				(justify left bottom)
			)
		)
		(property "Description" " "
			(at 0 0 270)
			(layer "F.Fab")
			(hide yes)
			(effects
				(font
					(size 1.27 1.27)
					(thickness 0.15)
				)
			)
		)
		(property "Author" "Antmicro"
			(at 42.658 307.394 0)
			(layer "F.Fab")
			(hide yes)
			(effects
				(font
					(size 1 1)
					(thickness 0.15)
				)
			)
		)
		(property "Dielectric" ""
			(at 42.658 307.394 0)
			(layer "F.Fab")
			(hide yes)
			(effects
				(font
					(size 1 1)
					(thickness 0.15)
				)
			)
		)
		(property "License" "Apache-2.0"
			(at 42.658 307.394 0)
			(layer "F.Fab")
			(hide yes)
			(effects
				(font
					(size 1 1)
					(thickness 0.15)
				)
			)
		)
		(property "MPN" "0603YD105KAT2A"
			(at 42.658 307.394 0)
			(layer "F.Fab")
			(hide yes)
			(effects
				(font
					(size 1 1)
					(thickness 0.15)
				)
			)
		)
		(property "Manufacturer" "Walsin"
			(at 42.658 307.394 0)
			(layer "F.Fab")
			(hide yes)
			(effects
				(font
					(size 1 1)
					(thickness 0.15)
				)
			)
		)
		(property "Val" "1u"
			(at 42.658 307.394 0)
			(layer "F.Fab")
			(hide yes)
			(effects
				(font
					(size 1 1)
					(thickness 0.15)
				)
			)
		)
		(property "Voltage" ""
			(at 42.658 307.394 0)
			(layer "F.Fab")
			(hide yes)
			(effects
				(font
					(size 1 1)
					(thickness 0.15)
				)
			)
		)
		(sheetname "Interfaces")
		(sheetfile "interfaces.kicad_sch")
		(attr smd)
		(fp_line
			(start -0.3 0.3)
			(end 0.3 0.3)
			(stroke
				(width 0.15)
				(type solid)
			)
			(layer "F.SilkS")
		)
		(fp_line
			(start -0.3 -0.3)
			(end 0.3 -0.3)
			(stroke
				(width 0.15)
				(type solid)
			)
			(layer "F.SilkS")
		)
		(fp_rect
			(start -1.24 -0.7)
			(end 1.24 0.7)
			(stroke
				(width 0.05)
				(type solid)
			)
			(fill no)
			(layer "F.CrtYd")
		)
		(fp_rect
			(start -0.8 -0.4)
			(end 0.8 0.4)
			(stroke
				(width 0.15)
				(type solid)
			)
			(fill no)
			(layer "F.Fab")
		)
		(pad "1" smd roundrect
			(at -0.7 0 270)
			(size 0.6 0.8)
			(layers "F.Cu" "F.Mask" "F.Paste")
			(roundrect_rratio 0.2)
			(net 5 "GND")
			(pintype "passive")
		)
		(pad "2" smd roundrect
			(at 0.7 0 270)
			(size 0.6 0.8)
			(layers "F.Cu" "F.Mask" "F.Paste")
			(roundrect_rratio 0.2)
			(net 459 "3V3_SYS")
			(pintype "passive")
		)
	)
	(footprint "antmicro-footprints:PinHeader_2x7_P2mm_Drill0.9mm_878311420"
		(layer "F.Cu")
		(at 214.160328 75.797157 90)
		(descr "2.00mm Pitch, Milli-Grid PCB Header, Dual Row, Vertical, Through Hole, Shrouded, 14 Circuits, 0.38µm Gold (Au) Plating, with Center Polarization Slot, with Locking Window, without PCB Locator, Tube")
		(tags "PINSTRIP, HEADER ")
		(property "Reference" "J4"
			(at 0 -4.6 90)
			(layer "F.SilkS")
			(effects
				(font
					(size 0.7 0.7)
					(thickness 0.15)
				)
				(justify left bottom)
			)
		)
		(property "Value" "PinHeader_2x7_P2mm_Drill0.9mm_878311420"
			(at 0 3.4 90)
			(layer "F.Fab")
			(effects
				(font
					(size 0.7 0.7)
					(thickness 0.15)
				)
				(justify left bottom)
			)
		)
		(property "Author" "Antmicro"
			(at 138.363171 289.957485 0)
			(layer "F.Fab")
			(hide yes)
			(effects
				(font
					(size 1 1)
					(thickness 0.15)
				)
			)
		)
		(property "License" "Apache-2.0"
			(at 138.363171 289.957485 0)
			(layer "F.Fab")
			(hide yes)
			(effects
				(font
					(size 1 1)
					(thickness 0.15)
				)
			)
		)
		(property "MPN" "0878311420"
			(at 138.363171 289.957485 0)
			(layer "F.Fab")
			(hide yes)
			(effects
				(font
					(size 1 1)
					(thickness 0.15)
				)
			)
		)
		(property "Manufacturer" "Molex"
			(at 138.363171 289.957485 0)
			(layer "F.Fab")
			(hide yes)
			(effects
				(font
					(size 1 1)
					(thickness 0.15)
				)
			)
		)
		(sheetname "Config SPI flash")
		(sheetfile "config-spi.kicad_sch")
		(attr through_hole)
		(fp_line
			(start 14.4 -4.2)
			(end 14.4 2.2)
			(stroke
				(width 0.15)
				(type solid)
			)
			(layer "F.SilkS")
		)
		(fp_line
			(start -2.4 -4.2)
			(end 14.4 -4.2)
			(stroke
				(width 0.15)
				(type solid)
			)
			(layer "F.SilkS")
		)
		(fp_line
			(start 14.4 2.2)
			(end 7.3 2.2)
			(stroke
				(width 0.15)
				(type solid)
			)
			(layer "F.SilkS")
		)
		(fp_line
			(start -2.4 2.2)
			(end -2.4 -4.2)
			(stroke
				(width 0.15)
				(type solid)
			)
			(layer "F.SilkS")
		)
		(fp_line
			(start -2.41 2.2)
			(end 4.7 2.2)
			(stroke
				(width 0.15)
				(type solid)
			)
			(layer "F.SilkS")
		)
		(fp_line
			(start -2.51 -4.34)
			(end 14.51 -4.34)
			(stroke
				(width 0.05)
				(type solid)
			)
			(layer "F.CrtYd")
		)
		(fp_line
			(start 14.51 2.34)
			(end 14.51 -4.34)
			(stroke
				(width 0.05)
				(type solid)
			)
			(layer "F.CrtYd")
		)
		(fp_line
			(start -2.51 2.34)
			(end -2.51 -4.34)
			(stroke
				(width 0.05)
				(type solid)
			)
			(layer "F.CrtYd")
		)
		(fp_line
			(start -2.51 2.34)
			(end 14.51 2.34)
			(stroke
				(width 0.05)
				(type solid)
			)
			(layer "F.CrtYd")
		)
		(fp_line
			(start 14.356 -4.15)
			(end -2.32 -4.15)
			(stroke
				(width 0.15)
				(type solid)
			)
			(layer "F.Fab")
		)
		(fp_line
			(start 14.356 1.898)
			(end 14.356 -4.15)
			(stroke
				(width 0.15)
				(type solid)
			)
			(layer "F.Fab")
		)
		(fp_line
			(start 14.356 2.15)
			(end -2.293 2.15)
			(stroke
				(width 0.15)
				(type solid)
			)
			(layer "F.Fab")
		)
		(fp_line
			(start -2.33 2.15)
			(end -2.33 -4.13)
			(stroke
				(width 0.15)
				(type solid)
			)
			(layer "F.Fab")
		)
		(fp_text user "Author: Antmicro"
			(at -14.7 9.2 90)
			(layer "F.Fab")
			(effects
				(font
					(size 0.7 0.7)
					(thickness 0.15)
				)
				(justify left bottom)
			)
		)
		(fp_text user "${REFERENCE}"
			(at -14.7 6.7 90)
			(layer "F.Fab")
			(effects
				(font
					(size 0.7 0.7)
					(thickness 0.15)
				)
				(justify left bottom)
			)
		)
		(fp_text user "License: Apache-2.0"
			(at -14.7 7.9 90)
			(layer "F.Fab")
			(effects
				(font
					(size 0.7 0.7)
					(thickness 0.15)
				)
				(justify left bottom)
			)
		)
		(pad "1" thru_hole rect
			(at 0 0 270)
			(size 1.6 1.6)
			(drill 0.9)
			(layers "*.Cu" "*.Mask")
			(remove_unused_layers no)
			(net 5 "GND")
			(pintype "passive")
		)
		(pad "2" thru_hole circle
			(at 0 -2 270)
			(size 1.6 1.6)
			(drill 0.9)
			(layers "*.Cu" "*.Mask")
			(remove_unused_layers no)
			(net 459 "3V3_SYS")
			(pintype "passive")
		)
		(pad "3" thru_hole circle
			(at 2 0 270)
			(size 1.6 1.6)
			(drill 0.9)
			(layers "*.Cu" "*.Mask")
			(remove_unused_layers no)
			(net 5 "GND")
			(pintype "passive")
		)
		(pad "4" thru_hole circle
			(at 2 -2 270)
			(size 1.6 1.6)
			(drill 0.9)
			(layers "*.Cu" "*.Mask")
			(remove_unused_layers no)
			(net 9 "TMS_JTAG")
			(pintype "passive")
		)
		(pad "5" thru_hole circle
			(at 4 0 270)
			(size 1.6 1.6)
			(drill 0.9)
			(layers "*.Cu" "*.Mask")
			(remove_unused_layers no)
			(net 5 "GND")
			(pintype "passive")
		)
		(pad "6" thru_hole circle
			(at 4 -2 270)
			(size 1.6 1.6)
			(drill 0.9)
			(layers "*.Cu" "*.Mask")
			(remove_unused_layers no)
			(net 8 "TCK_JTAG")
			(pintype "passive")
		)
		(pad "7" thru_hole circle
			(at 6 0 270)
			(size 1.6 1.6)
			(drill 0.9)
			(layers "*.Cu" "*.Mask")
			(remove_unused_layers no)
			(net 5 "GND")
			(pintype "passive")
		)
		(pad "8" thru_hole circle
			(at 6 -2 270)
			(size 1.6 1.6)
			(drill 0.9)
			(layers "*.Cu" "*.Mask")
			(remove_unused_layers no)
			(net 11 "TDO_JTAG")
			(pintype "passive")
		)
		(pad "9" thru_hole circle
			(at 8 0 270)
			(size 1.6 1.6)
			(drill 0.9)
			(layers "*.Cu" "*.Mask")
			(remove_unused_layers no)
			(net 5 "GND")
			(pintype "passive")
		)
		(pad "10" thru_hole circle
			(at 8 -2 270)
			(size 1.6 1.6)
			(drill 0.9)
			(layers "*.Cu" "*.Mask")
			(remove_unused_layers no)
			(net 10 "TDI_JTAG")
			(pintype "passive")
		)
		(pad "11" thru_hole circle
			(at 10 0 270)
			(size 1.6 1.6)
			(drill 0.9)
			(layers "*.Cu" "*.Mask")
			(remove_unused_layers no)
			(net 5 "GND")
			(pintype "passive")
		)
		(pad "12" thru_hole circle
			(at 10 -2 270)
			(size 1.6 1.6)
			(drill 0.9)
			(layers "*.Cu" "*.Mask")
			(remove_unused_layers no)
			(net 86 "unconnected-(J4-Pad12)")
			(pintype "passive+no_connect")
		)
		(pad "13" thru_hole circle
			(at 12 0 270)
			(size 1.6 1.6)
			(drill 0.9)
			(layers "*.Cu" "*.Mask")
			(remove_unused_layers no)
			(net 5 "GND")
			(pintype "passive")
		)
		(pad "14" thru_hole circle
			(at 12 -2 270)
			(size 1.6 1.6)
			(drill 0.9)
			(layers "*.Cu" "*.Mask")
			(remove_unused_layers no)
			(net 87 "unconnected-(J4-Pad14)")
			(pintype "passive+no_connect")
		)
	)
	(footprint "antmicro-footprints:C_0402_1005Metric"
		(layer "F.Cu")
		(at 180.995 112.429 -90)
		(descr "Capacitor SMD 0402")
		(tags "capacitor SMD 0402")
		(property "Reference" "C5"
			(at -0.829 -0.405 270)
			(layer "F.SilkS")
			(effects
				(font
					(size 0.7 0.7)
					(thickness 0.15)
				)
				(justify left bottom)
			)
		)
		(property "Value" "C_100n_6V3_0402"
			(at 0 1.4 270)
			(layer "F.Fab")
			(effects
				(font
					(size 0.7 0.7)
					(thickness 0.15)
				)
				(justify left bottom)
			)
		)
		(property "Description" " "
			(at 0 0 270)
			(layer "F.Fab")
			(hide yes)
			(effects
				(font
					(size 1.27 1.27)
					(thickness 0.15)
				)
			)
		)
		(property "Author" "Antmicro"
			(at 68.566 293.424 0)
			(layer "F.Fab")
			(hide yes)
			(effects
				(font
					(size 1 1)
					(thickness 0.15)
				)
			)
		)
		(property "Dielectric" ""
			(at 68.566 293.424 0)
			(layer "F.Fab")
			(hide yes)
			(effects
				(font
					(size 1 1)
					(thickness 0.15)
				)
			)
		)
		(property "License" "Apache-2.0"
			(at 68.566 293.424 0)
			(layer "F.Fab")
			(hide yes)
			(effects
				(font
					(size 1 1)
					(thickness 0.15)
				)
			)
		)
		(property "MPN" "0402X104K6R3CT"
			(at 68.566 293.424 0)
			(layer "F.Fab")
			(hide yes)
			(effects
				(font
					(size 1 1)
					(thickness 0.15)
				)
			)
		)
		(property "Manufacturer" "Walsin"
			(at 68.566 293.424 0)
			(layer "F.Fab")
			(hide yes)
			(effects
				(font
					(size 1 1)
					(thickness 0.15)
				)
			)
		)
		(property "Val" "100n"
			(at 68.566 293.424 0)
			(layer "F.Fab")
			(hide yes)
			(effects
				(font
					(size 1 1)
					(thickness 0.15)
				)
			)
		)
		(property "Voltage" ""
			(at 68.566 293.424 0)
			(layer "F.Fab")
			(hide yes)
			(effects
				(font
					(size 1 1)
					(thickness 0.15)
				)
			)
		)
		(sheetname "FPGA Banks")
		(sheetfile "fpga-banks.kicad_sch")
		(attr smd)
		(fp_rect
			(start -0.94 -0.47)
			(end 0.94 0.47)
			(stroke
				(width 0.05)
				(type solid)
			)
			(fill no)
			(layer "F.CrtYd")
		)
		(fp_rect
			(start -0.499 -0.249)
			(end 0.499 0.249)
			(stroke
				(width 0.15)
				(type solid)
			)
			(fill no)
			(layer "F.Fab")
		)
		(pad "1" smd roundrect
			(at -0.484 0 270)
			(size 0.59 0.64)
			(layers "F.Cu" "F.Mask" "F.Paste")
			(roundrect_rratio 0.25)
			(net 5 "GND")
			(pintype "passive")
		)
		(pad "2" smd roundrect
			(at 0.484 0 270)
			(size 0.59 0.64)
			(layers "F.Cu" "F.Mask" "F.Paste")
			(roundrect_rratio 0.25)
			(net 459 "3V3_SYS")
			(pintype "passive")
		)
	)
	(footprint "antmicro-footprints:R_0402_1005Metric"
		(layer "F.Cu")
		(at 197.486328 86.720008 90)
		(descr "Resistor SMD 0402")
		(tags "resistor SMD 0402")
		(property "Reference" "R66"
			(at -1.279992 -0.486328 90)
			(layer "F.SilkS")
			(effects
				(font
					(size 0.7 0.7)
					(thickness 0.15)
				)
				(justify left bottom)
			)
		)
		(property "Value" "R_4k7_0402"
			(at 0 1.4 90)
			(layer "F.Fab")
			(effects
				(font
					(size 0.7 0.7)
					(thickness 0.15)
				)
				(justify left bottom)
			)
		)
		(property "Description" "4k7 resistor in 0402 package with 1% tolerance"
			(at 0 0 90)
			(layer "F.Fab")
			(hide yes)
			(effects
				(font
					(size 1.27 1.27)
					(thickness 0.15)
				)
			)
		)
		(property "Author" "Antmicro"
			(at 284.206336 -110.76632 0)
			(layer "F.Fab")
			(hide yes)
			(effects
				(font
					(size 1 1)
					(thickness 0.15)
				)
			)
		)
		(property "License" "Apache-2.0"
			(at 284.206336 -110.76632 0)
			(layer "F.Fab")
			(hide yes)
			(effects
				(font
					(size 1 1)
					(thickness 0.15)
				)
			)
		)
		(property "MPN" "CR0402-FX-4701GLF"
			(at 284.206336 -110.76632 0)
			(layer "F.Fab")
			(hide yes)
			(effects
				(font
					(size 1 1)
					(thickness 0.15)
				)
			)
		)
		(property "Manufacturer" "Bourns"
			(at 284.206336 -110.76632 0)
			(layer "F.Fab")
			(hide yes)
			(effects
				(font
					(size 1 1)
					(thickness 0.15)
				)
			)
		)
		(property "Tolerance" "1%"
			(at 284.206336 -110.76632 0)
			(layer "F.Fab")
			(hide yes)
			(effects
				(font
					(size 1 1)
					(thickness 0.15)
				)
			)
		)
		(property "Val" "4k7"
			(at 284.206336 -110.76632 0)
			(layer "F.Fab")
			(hide yes)
			(effects
				(font
					(size 1 1)
					(thickness 0.15)
				)
			)
		)
		(sheetname "Config SPI flash")
		(sheetfile "config-spi.kicad_sch")
		(attr smd)
		(fp_rect
			(start -0.93 -0.47)
			(end 0.93 0.47)
			(stroke
				(width 0.05)
				(type solid)
			)
			(fill no)
			(layer "F.CrtYd")
		)
		(fp_rect
			(start -0.5 -0.25)
			(end 0.5 0.25)
			(stroke
				(width 0.15)
				(type solid)
			)
			(fill no)
			(layer "F.Fab")
		)
		(pad "1" smd roundrect
			(at -0.485 0 90)
			(size 0.59 0.64)
			(layers "F.Cu" "F.Mask" "F.Paste")
			(roundrect_rratio 0.25)
			(net 459 "3V3_SYS")
			(pintype "passive")
		)
		(pad "2" smd roundrect
			(at 0.485 0 90)
			(size 0.59 0.64)
			(layers "F.Cu" "F.Mask" "F.Paste")
			(roundrect_rratio 0.25)
			(net 210 "INIT_B")
			(pintype "passive")
		)
	)
)
